(kicad_pcb
	(version 20260206)
	(generator "pcbnew")
	(generator_version "10.0")
	(general
		(thickness 1.6)
		(legacy_teardrops no)
	)
	(paper "A4")
	(title_block
		(title "Wiwynn_Tioga_Pass_MB.brd")
		(comment 1 "Tioga Pass / footprints 1057-1063 of 4770")
	)
	(layers
		(0 "F.Cu" signal "TOP")
		(4 "In1.Cu" signal "L2GND")
		(6 "In2.Cu" signal "L3")
		(8 "In3.Cu" signal "L4GND")
		(10 "In4.Cu" signal "L5")
		(12 "In5.Cu" signal "L6GND")
		(14 "In6.Cu" signal "L7VCC")
		(16 "In7.Cu" signal "L8VCC")
		(18 "In8.Cu" signal "L9GND")
		(20 "In9.Cu" signal "L10")
		(22 "In10.Cu" signal "L11GND")
		(24 "In11.Cu" signal "L12")
		(26 "In12.Cu" signal "L13GND")
		(2 "B.Cu" signal "BOTTOM")
		(9 "F.Adhes" user "F.Adhesive")
		(11 "B.Adhes" user "B.Adhesive")
		(13 "F.Paste" user "Package Geometry/Pastemask Top")
		(15 "B.Paste" user "Package Geometry/Pastemask Bottom")
		(5 "F.SilkS" user "Ref Des/Silkscreen Top")
		(7 "B.SilkS" user "Ref Des/Silkscreen Bottom")
		(1 "F.Mask" user "Board Geometry/Soldermask Top")
		(3 "B.Mask" user "Board Geometry/Soldermask Bottom")
		(17 "Dwgs.User" user "User.Drawings")
		(19 "Cmts.User" user "User.Comments")
		(21 "Eco1.User" user "User.Eco1")
		(23 "Eco2.User" user "User.Eco2")
		(25 "Edge.Cuts" user "Board Geometry/Outline")
		(27 "Margin" user)
		(31 "F.CrtYd" user "Package Geometry/Place Bound Top")
		(29 "B.CrtYd" user "Package Geometry/Place Bound Bottom")
		(35 "F.Fab" user "Ref Des/Assembly Top")
		(33 "B.Fab" user "Ref Des/Assembly Bottom")
	)
	(footprint ""
		(layer "F.Cu")
		(at -2.28346 -131.96316 180)
		(property "Reference" "R1B4"
			(at 0 0 180)
			(layer "F.SilkS")
			(hide yes)
			(effects
				(font
					(size 1.27 1.27)
				)
			)
		)
		(property "Value" ""
			(at 0 0 180)
			(layer "F.Fab")
			(effects
				(font
					(size 1.27 1.27)
				)
			)
		)
		(duplicate_pad_numbers_are_jumpers no)
		(fp_poly
			(pts
				(xy -0.2794 -0.1016) (xy 0.2794 -0.1016) (xy 0.2794 0.9906) (xy -0.2794 0.9906)
			)
			(stroke
				(width 0)
				(type default)
			)
			(fill no)
			(layer "F.CrtYd")
		)
		(fp_line
			(start 0.2794 0.9906)
			(end 0.2794 -0.1016)
			(stroke
				(width 0.1)
				(type default)
			)
			(layer "F.Fab")
		)
		(fp_line
			(start 0.2794 -0.1016)
			(end -0.2794 -0.1016)
			(stroke
				(width 0.1)
				(type default)
			)
			(layer "F.Fab")
		)
		(fp_line
			(start -0.2794 0.9906)
			(end 0.2794 0.9906)
			(stroke
				(width 0.1)
				(type default)
			)
			(layer "F.Fab")
		)
		(fp_line
			(start -0.2794 -0.1016)
			(end -0.2794 0.9906)
			(stroke
				(width 0.1)
				(type default)
			)
			(layer "F.Fab")
		)
		(pad "1" smd rect
			(at 0 0 180)
			(size 0.508 0.508)
			(layers "F.Cu" "F.Mask" "F.Paste")
			(net "IRQ_PVDDQ_KLM_VRHOT_LVT3_R_N")
		)
		(pad "2" smd rect
			(at 0 0.889 180)
			(size 0.508 0.508)
			(layers "F.Cu" "F.Mask" "F.Paste")
			(net "IRQ_PVDDQ_KLM_VRHOT_LVT3_N")
		)
		(zone
			(layer "F.Cu")
			(hatch none 0.5)
			(connect_pads
				(clearance 0)
			)
			(min_thickness 0.25)
			(keepout
				(tracks not_allowed)
				(vias allowed)
				(pads allowed)
				(copperpour not_allowed)
				(footprints allowed)
			)
			(placement
				(enabled no)
				(sheetname "")
			)
			(fill
				(thermal_gap 0.5)
				(thermal_bridge_width 0.5)
				(island_removal_mode 0)
			)
			(polygon
				(pts
					(xy -2.02946 -132.59816) (xy -2.53746 -132.59816) (xy -2.53746 -132.21716) (xy -2.02946 -132.21716)
				)
			)
		)
		(zone
			(layer "F.Cu")
			(hatch none 0.5)
			(connect_pads
				(clearance 0)
			)
			(min_thickness 0.25)
			(keepout
				(tracks allowed)
				(vias not_allowed)
				(pads allowed)
				(copperpour not_allowed)
				(footprints allowed)
			)
			(placement
				(enabled no)
				(sheetname "")
			)
			(fill
				(thermal_gap 0.5)
				(thermal_bridge_width 0.5)
				(island_removal_mode 0)
			)
			(polygon
				(pts
					(xy -2.02946 -132.21716) (xy -2.53746 -132.21716) (xy -2.53746 -132.59816) (xy -2.02946 -132.59816)
				)
			)
		)
	)
	(footprint ""
		(layer "F.Cu")
		(at 33.127696 -69.4182 90)
		(property "Reference" "C1D16"
			(at 0 0 90)
			(layer "F.SilkS")
			(hide yes)
			(effects
				(font
					(size 1.27 1.27)
				)
			)
		)
		(property "Value" ""
			(at 0 0 90)
			(layer "F.Fab")
			(effects
				(font
					(size 1.27 1.27)
				)
			)
		)
		(duplicate_pad_numbers_are_jumpers no)
		(fp_rect
			(start 0.3048 0.9906)
			(end -0.3048 -0.1016)
			(stroke
				(width 0)
				(type default)
			)
			(fill no)
			(layer "F.CrtYd")
		)
		(fp_line
			(start 0.3048 -0.1016)
			(end -0.3048 -0.1016)
			(stroke
				(width 0.1)
				(type default)
			)
			(layer "F.Fab")
		)
		(fp_line
			(start -0.3048 -0.1016)
			(end -0.3048 0.9906)
			(stroke
				(width 0.1)
				(type default)
			)
			(layer "F.Fab")
		)
		(fp_line
			(start 0.3048 0.9906)
			(end 0.3048 -0.1016)
			(stroke
				(width 0.1)
				(type default)
			)
			(layer "F.Fab")
		)
		(fp_line
			(start -0.3048 0.9906)
			(end 0.3048 0.9906)
			(stroke
				(width 0.1)
				(type default)
			)
			(layer "F.Fab")
		)
		(pad "1" smd rect
			(at 0 0 90)
			(size 0.508 0.508)
			(layers "F.Cu" "F.Mask" "F.Paste")
			(net "P5V_STBY")
		)
		(pad "2" smd rect
			(at 0 0.889 90)
			(size 0.508 0.508)
			(layers "F.Cu" "F.Mask" "F.Paste")
			(net "GND")
		)
		(zone
			(layer "F.Cu")
			(hatch none 0.5)
			(connect_pads
				(clearance 0)
			)
			(min_thickness 0.25)
			(keepout
				(tracks allowed)
				(vias not_allowed)
				(pads allowed)
				(copperpour not_allowed)
				(footprints allowed)
			)
			(placement
				(enabled no)
				(sheetname "")
			)
			(fill
				(thermal_gap 0.5)
				(thermal_bridge_width 0.5)
				(island_removal_mode 0)
			)
			(polygon
				(pts
					(xy 33.762696 -69.6722) (xy 33.381696 -69.6722) (xy 33.381696 -69.1642) (xy 33.762696 -69.1642)
				)
			)
		)
		(zone
			(layer "F.Cu")
			(hatch none 0.5)
			(connect_pads
				(clearance 0)
			)
			(min_thickness 0.25)
			(keepout
				(tracks not_allowed)
				(vias allowed)
				(pads allowed)
				(copperpour not_allowed)
				(footprints allowed)
			)
			(placement
				(enabled no)
				(sheetname "")
			)
			(fill
				(thermal_gap 0.5)
				(thermal_bridge_width 0.5)
				(island_removal_mode 0)
			)
			(polygon
				(pts
					(xy 33.762696 -69.6722) (xy 33.381696 -69.6722) (xy 33.381696 -69.1642) (xy 33.762696 -69.1642)
				)
			)
		)
	)
	(footprint ""
		(layer "F.Cu")
		(at 245.7577 -3.3528 -90)
		(property "Reference" "C5G11"
			(at 1.848866 0.752348 270)
			(unlocked yes)
			(layer "F.SilkS")
			(effects
				(font
					(size 1.27 0.9652)
					(thickness 0.1524)
				)
			)
		)
		(property "Value" ""
			(at 0 0 270)
			(layer "F.Fab")
			(effects
				(font
					(size 1.27 1.27)
				)
			)
		)
		(duplicate_pad_numbers_are_jumpers no)
		(fp_rect
			(start -0.500126 1.598422)
			(end 0.500126 -0.201422)
			(stroke
				(width 0)
				(type default)
			)
			(fill no)
			(layer "F.CrtYd")
		)
		(fp_line
			(start -0.500126 1.598422)
			(end -0.500126 -0.201422)
			(stroke
				(width 0.1)
				(type default)
			)
			(layer "F.Fab")
		)
		(fp_line
			(start 0.500126 1.598422)
			(end -0.500126 1.598422)
			(stroke
				(width 0.1)
				(type default)
			)
			(layer "F.Fab")
		)
		(fp_line
			(start -0.500126 -0.201422)
			(end 0.500126 -0.201422)
			(stroke
				(width 0.1)
				(type default)
			)
			(layer "F.Fab")
		)
		(fp_line
			(start 0.500126 -0.201422)
			(end 0.500126 1.598422)
			(stroke
				(width 0.1)
				(type default)
			)
			(layer "F.Fab")
		)
		(pad "1" smd rect
			(at 0 0 180)
			(size 0.889 0.9906)
			(layers "F.Cu" "F.Mask" "F.Paste")
			(net "PVDDQ_ABC")
		)
		(pad "2" smd rect
			(at 0 1.397 180)
			(size 0.889 0.9906)
			(layers "F.Cu" "F.Mask" "F.Paste")
			(net "GND")
		)
		(zone
			(layer "F.Cu")
			(hatch none 0.5)
			(connect_pads
				(clearance 0)
			)
			(min_thickness 0.25)
			(keepout
				(tracks allowed)
				(vias not_allowed)
				(pads allowed)
				(copperpour not_allowed)
				(footprints allowed)
			)
			(placement
				(enabled no)
				(sheetname "")
			)
			(fill
				(thermal_gap 0.5)
				(thermal_bridge_width 0.5)
				(island_removal_mode 0)
			)
			(polygon
				(pts
					(xy 244.8052 -3.8481) (xy 244.8052 -2.8575) (xy 245.3132 -2.8575) (xy 245.3132 -3.8481)
				)
			)
		)
		(zone
			(layer "F.Cu")
			(hatch none 0.5)
			(connect_pads
				(clearance 0)
			)
			(min_thickness 0.25)
			(keepout
				(tracks not_allowed)
				(vias allowed)
				(pads allowed)
				(copperpour not_allowed)
				(footprints allowed)
			)
			(placement
				(enabled no)
				(sheetname "")
			)
			(fill
				(thermal_gap 0.5)
				(thermal_bridge_width 0.5)
				(island_removal_mode 0)
			)
			(polygon
				(pts
					(xy 244.8052 -3.8481) (xy 244.8052 -2.8575) (xy 245.3132 -2.8575) (xy 245.3132 -3.8481)
				)
			)
		)
	)
	(footprint ""
		(layer "F.Cu")
		(at 413.3215 -113.411 -90)
		(property "Reference" "R2L4"
			(at 0 0 270)
			(layer "F.SilkS")
			(hide yes)
			(effects
				(font
					(size 1.27 1.27)
				)
			)
		)
		(property "Value" ""
			(at 0 0 270)
			(layer "F.Fab")
			(effects
				(font
					(size 1.27 1.27)
				)
			)
		)
		(duplicate_pad_numbers_are_jumpers no)
		(fp_poly
			(pts
				(xy -0.2794 -0.1016) (xy 0.2794 -0.1016) (xy 0.2794 0.9906) (xy -0.2794 0.9906)
			)
			(stroke
				(width 0)
				(type default)
			)
			(fill no)
			(layer "F.CrtYd")
		)
		(fp_line
			(start -0.2794 0.9906)
			(end 0.2794 0.9906)
			(stroke
				(width 0.1)
				(type default)
			)
			(layer "F.Fab")
		)
		(fp_line
			(start 0.2794 0.9906)
			(end 0.2794 -0.1016)
			(stroke
				(width 0.1)
				(type default)
			)
			(layer "F.Fab")
		)
		(fp_line
			(start -0.2794 -0.1016)
			(end -0.2794 0.9906)
			(stroke
				(width 0.1)
				(type default)
			)
			(layer "F.Fab")
		)
		(fp_line
			(start 0.2794 -0.1016)
			(end -0.2794 -0.1016)
			(stroke
				(width 0.1)
				(type default)
			)
			(layer "F.Fab")
		)
		(pad "1" smd rect
			(at 0 0 270)
			(size 0.508 0.508)
			(layers "F.Cu" "F.Mask" "F.Paste")
			(net "P3V3_STBY")
		)
		(pad "2" smd rect
			(at 0 0.889 270)
			(size 0.508 0.508)
			(layers "F.Cu" "F.Mask" "F.Paste")
			(net "SGPIO_PCH_SSATA_DOUT0_R")
		)
		(zone
			(layer "F.Cu")
			(hatch none 0.5)
			(connect_pads
				(clearance 0)
			)
			(min_thickness 0.25)
			(keepout
				(tracks not_allowed)
				(vias allowed)
				(pads allowed)
				(copperpour not_allowed)
				(footprints allowed)
			)
			(placement
				(enabled no)
				(sheetname "")
			)
			(fill
				(thermal_gap 0.5)
				(thermal_bridge_width 0.5)
				(island_removal_mode 0)
			)
			(polygon
				(pts
					(xy 412.6865 -113.665) (xy 412.6865 -113.157) (xy 413.0675 -113.157) (xy 413.0675 -113.665)
				)
			)
		)
		(zone
			(layer "F.Cu")
			(hatch none 0.5)
			(connect_pads
				(clearance 0)
			)
			(min_thickness 0.25)
			(keepout
				(tracks allowed)
				(vias not_allowed)
				(pads allowed)
				(copperpour not_allowed)
				(footprints allowed)
			)
			(placement
				(enabled no)
				(sheetname "")
			)
			(fill
				(thermal_gap 0.5)
				(thermal_bridge_width 0.5)
				(island_removal_mode 0)
			)
			(polygon
				(pts
					(xy 413.0675 -113.665) (xy 413.0675 -113.157) (xy 412.6865 -113.157) (xy 412.6865 -113.665)
				)
			)
		)
	)
	(footprint ""
		(layer "F.Cu")
		(at 485.9274 -136.652 -90)
		(property "Reference" "DS9A6"
			(at -0.19304 3.36169 90)
			(unlocked yes)
			(layer "F.SilkS")
			(effects
				(font
					(size 0.7874 0.5842)
					(thickness 0.1524)
				)
			)
		)
		(property "Value" ""
			(at 0 0 270)
			(layer "F.Fab")
			(effects
				(font
					(size 1.27 1.27)
				)
			)
		)
		(duplicate_pad_numbers_are_jumpers no)
		(fp_line
			(start -1.78562 5.26796)
			(end -1.78562 4.144518)
			(stroke
				(width 0.1524)
				(type default)
			)
			(layer "F.SilkS")
		)
		(fp_line
			(start -2.266442 4.144518)
			(end -1.304798 4.144518)
			(stroke
				(width 0.1524)
				(type default)
			)
			(layer "F.SilkS")
		)
		(fp_line
			(start -1.78562 4.144518)
			(end -2.266442 3.311652)
			(stroke
				(width 0.1524)
				(type default)
			)
			(layer "F.SilkS")
		)
		(fp_line
			(start -2.266442 3.311652)
			(end -1.78562 3.311652)
			(stroke
				(width 0.1524)
				(type default)
			)
			(layer "F.SilkS")
		)
		(fp_line
			(start -1.78562 3.311652)
			(end -1.304798 3.311652)
			(stroke
				(width 0.1524)
				(type default)
			)
			(layer "F.SilkS")
		)
		(fp_line
			(start -1.304798 3.311652)
			(end -1.78562 4.144518)
			(stroke
				(width 0.1524)
				(type default)
			)
			(layer "F.SilkS")
		)
		(fp_line
			(start -1.78562 2.400046)
			(end -1.78562 3.311652)
			(stroke
				(width 0.1524)
				(type default)
			)
			(layer "F.SilkS")
		)
		(fp_poly
			(pts
				(xy 0.6223 2.032) (xy -0.6223 2.032) (xy -0.6223 0.0254) (xy 0.6223 0.0254)
			)
			(stroke
				(width 0)
				(type default)
			)
			(fill no)
			(layer "F.CrtYd")
		)
		(fp_line
			(start -2.266442 4.144518)
			(end -1.304798 4.144518)
			(stroke
				(width 0.1)
				(type default)
			)
			(layer "F.Fab")
		)
		(fp_line
			(start -1.78562 4.144518)
			(end -1.78562 5.26796)
			(stroke
				(width 0.1)
				(type default)
			)
			(layer "F.Fab")
		)
		(fp_line
			(start -1.78562 4.144518)
			(end -2.266442 3.311652)
			(stroke
				(width 0.1)
				(type default)
			)
			(layer "F.Fab")
		)
		(fp_line
			(start -1.782318 3.314446)
			(end -1.782318 2.40284)
			(stroke
				(width 0.1)
				(type default)
			)
			(layer "F.Fab")
		)
		(fp_line
			(start -2.266442 3.311652)
			(end -1.304798 3.311652)
			(stroke
				(width 0.1)
				(type default)
			)
			(layer "F.Fab")
		)
		(fp_line
			(start -1.304798 3.311652)
			(end -1.78562 4.144518)
			(stroke
				(width 0.1)
				(type default)
			)
			(layer "F.Fab")
		)
		(fp_line
			(start -0.6223 2.032)
			(end -0.6223 0.0254)
			(stroke
				(width 0.1)
				(type default)
			)
			(layer "F.Fab")
		)
		(fp_line
			(start 0.6223 2.032)
			(end -0.6223 2.032)
			(stroke
				(width 0.1)
				(type default)
			)
			(layer "F.Fab")
		)
		(fp_line
			(start -0.6223 0.0254)
			(end 0.6223 0.0254)
			(stroke
				(width 0.1)
				(type default)
			)
			(layer "F.Fab")
		)
		(fp_line
			(start 0.6223 0.0254)
			(end 0.6223 2.032)
			(stroke
				(width 0.1)
				(type default)
			)
			(layer "F.Fab")
		)
		(pad "1" smd rect
			(at 0 0 270)
			(size 1.27 1.27)
			(layers "F.Cu" "F.Mask" "F.Paste")
			(net "LED_P5V_STBY")
		)
		(pad "2" smd rect
			(at 0 2.032 270)
			(size 1.27 1.27)
			(layers "F.Cu" "F.Mask" "F.Paste")
			(net "GND")
		)
		(zone
			(layer "F.Cu")
			(hatch none 0.5)
			(connect_pads
				(clearance 0)
			)
			(min_thickness 0.25)
			(keepout
				(tracks not_allowed)
				(vias allowed)
				(pads allowed)
				(copperpour not_allowed)
				(footprints allowed)
			)
			(placement
				(enabled no)
				(sheetname "")
			)
			(fill
				(thermal_gap 0.5)
				(thermal_bridge_width 0.5)
				(island_removal_mode 0)
			)
			(polygon
				(pts
					(xy 484.5304 -137.287) (xy 484.5304 -136.017) (xy 485.2924 -136.017) (xy 485.2924 -137.287)
				)
			)
		)
		(zone
			(layer "F.Cu")
			(hatch none 0.5)
			(connect_pads
				(clearance 0)
			)
			(min_thickness 0.25)
			(keepout
				(tracks allowed)
				(vias not_allowed)
				(pads allowed)
				(copperpour not_allowed)
				(footprints allowed)
			)
			(placement
				(enabled no)
				(sheetname "")
			)
			(fill
				(thermal_gap 0.5)
				(thermal_bridge_width 0.5)
				(island_removal_mode 0)
			)
			(polygon
				(pts
					(xy 484.5304 -137.287) (xy 484.5304 -136.017) (xy 485.2924 -136.017) (xy 485.2924 -137.287)
				)
			)
		)
	)
	(footprint ""
		(layer "F.Cu")
		(at 397.9672 1.7272 90)
		(property "Reference" "R8G22"
			(at 0 0 90)
			(layer "F.SilkS")
			(hide yes)
			(effects
				(font
					(size 1.27 1.27)
				)
			)
		)
		(property "Value" ""
			(at 0 0 90)
			(layer "F.Fab")
			(effects
				(font
					(size 1.27 1.27)
				)
			)
		)
		(duplicate_pad_numbers_are_jumpers no)
		(fp_poly
			(pts
				(xy -0.2794 -0.1016) (xy 0.2794 -0.1016) (xy 0.2794 0.9906) (xy -0.2794 0.9906)
			)
			(stroke
				(width 0)
				(type default)
			)
			(fill no)
			(layer "F.CrtYd")
		)
		(fp_line
			(start 0.2794 -0.1016)
			(end -0.2794 -0.1016)
			(stroke
				(width 0.1)
				(type default)
			)
			(layer "F.Fab")
		)
		(fp_line
			(start -0.2794 -0.1016)
			(end -0.2794 0.9906)
			(stroke
				(width 0.1)
				(type default)
			)
			(layer "F.Fab")
		)
		(fp_line
			(start 0.2794 0.9906)
			(end 0.2794 -0.1016)
			(stroke
				(width 0.1)
				(type default)
			)
			(layer "F.Fab")
		)
		(fp_line
			(start -0.2794 0.9906)
			(end 0.2794 0.9906)
			(stroke
				(width 0.1)
				(type default)
			)
			(layer "F.Fab")
		)
		(pad "1" smd rect
			(at 0 0 90)
			(size 0.508 0.508)
			(layers "F.Cu" "F.Mask" "F.Paste")
			(net "JTAG_TCK")
		)
		(pad "2" smd rect
			(at 0 0.889 90)
			(size 0.508 0.508)
			(layers "F.Cu" "F.Mask" "F.Paste")
			(net "JTAG_TCK_R")
		)
		(zone
			(layer "F.Cu")
			(hatch none 0.5)
			(connect_pads
				(clearance 0)
			)
			(min_thickness 0.25)
			(keepout
				(tracks allowed)
				(vias not_allowed)
				(pads allowed)
				(copperpour not_allowed)
				(footprints allowed)
			)
			(placement
				(enabled no)
				(sheetname "")
			)
			(fill
				(thermal_gap 0.5)
				(thermal_bridge_width 0.5)
				(island_removal_mode 0)
			)
			(polygon
				(pts
					(xy 398.2212 1.9812) (xy 398.2212 1.4732) (xy 398.6022 1.4732) (xy 398.6022 1.9812)
				)
			)
		)
		(zone
			(layer "F.Cu")
			(hatch none 0.5)
			(connect_pads
				(clearance 0)
			)
			(min_thickness 0.25)
			(keepout
				(tracks not_allowed)
				(vias allowed)
				(pads allowed)
				(copperpour not_allowed)
				(footprints allowed)
			)
			(placement
				(enabled no)
				(sheetname "")
			)
			(fill
				(thermal_gap 0.5)
				(thermal_bridge_width 0.5)
				(island_removal_mode 0)
			)
			(polygon
				(pts
					(xy 398.6022 1.9812) (xy 398.6022 1.4732) (xy 398.2212 1.4732) (xy 398.2212 1.9812)
				)
			)
		)
	)
	(footprint ""
		(layer "F.Cu")
		(at -1.864868 -140.939012 -90)
		(property "Reference" "C1A19"
			(at 0 0 270)
			(layer "F.SilkS")
			(hide yes)
			(effects
				(font
					(size 1.27 1.27)
				)
			)
		)
		(property "Value" ""
			(at 0 0 270)
			(layer "F.Fab")
			(effects
				(font
					(size 1.27 1.27)
				)
			)
		)
		(duplicate_pad_numbers_are_jumpers no)
		(fp_poly
			(pts
				(xy 0.3048 -0.1016) (xy 0.3048 0.9906) (xy -0.3048 0.9906) (xy -0.3048 -0.1016)
			)
			(stroke
				(width 0)
				(type default)
			)
			(fill no)
			(layer "F.CrtYd")
		)
		(fp_line
			(start -0.3048 0.9906)
			(end 0.3048 0.9906)
			(stroke
				(width 0.1)
				(type default)
			)
			(layer "F.Fab")
		)
		(fp_line
			(start 0.3048 0.9906)
			(end 0.3048 -0.1016)
			(stroke
				(width 0.1)
				(type default)
			)
			(layer "F.Fab")
		)
		(fp_line
			(start -0.3048 -0.1016)
			(end -0.3048 0.9906)
			(stroke
				(width 0.1)
				(type default)
			)
			(layer "F.Fab")
		)
		(fp_line
			(start 0.3048 -0.1016)
			(end -0.3048 -0.1016)
			(stroke
				(width 0.1)
				(type default)
			)
			(layer "F.Fab")
		)
		(pad "1" smd rect
			(at 0 0 270)
			(size 0.508 0.508)
			(layers "F.Cu" "F.Mask" "F.Paste")
			(net "VR_FET_SW_P12V_STBY_PVDDQ_KLM")
		)
		(pad "2" smd rect
			(at 0 0.889 270)
			(size 0.508 0.508)
			(layers "F.Cu" "F.Mask" "F.Paste")
			(net "GND")
		)
		(zone
			(layer "F.Cu")
			(hatch none 0.5)
			(connect_pads
				(clearance 0)
			)
			(min_thickness 0.25)
			(keepout
				(tracks not_allowed)
				(vias allowed)
				(pads allowed)
				(copperpour not_allowed)
				(footprints allowed)
			)
			(placement
				(enabled no)
				(sheetname "")
			)
			(fill
				(thermal_gap 0.5)
				(thermal_bridge_width 0.5)
				(island_removal_mode 0)
			)
			(polygon
				(pts
					(xy -2.499868 -141.193012) (xy -2.499868 -140.685012) (xy -2.118868 -140.685012) (xy -2.118868 -141.193012)
				)
			)
		)
		(zone
			(layer "F.Cu")
			(hatch none 0.5)
			(connect_pads
				(clearance 0)
			)
			(min_thickness 0.25)
			(keepout
				(tracks allowed)
				(vias not_allowed)
				(pads allowed)
				(copperpour not_allowed)
				(footprints allowed)
			)
			(placement
				(enabled no)
				(sheetname "")
			)
			(fill
				(thermal_gap 0.5)
				(thermal_bridge_width 0.5)
				(island_removal_mode 0)
			)
			(polygon
				(pts
					(xy -2.118868 -141.193012) (xy -2.118868 -140.685012) (xy -2.499868 -140.685012) (xy -2.499868 -141.193012)
				)
			)
		)
	)
)
